# BASEBOARD_FAB2 (Tioga Pass) — schematic netlist excerpt (pin names and nets, part order shuffled) for the footprints in the layout excerpt that follows; sources: Cadence DE-HDL packaged netlist, KiCad conversion of Wiwynn_Tioga_Pass_MB.brd

R6B1  RES  49.9 1% CHIP  pkg 0402  page 21 : A = PVCCIO_CPU0 ; B = SVID_ALERT1_CPU0_R_N
R6D13  RES  240 1.0% EMPTY  pkg 0402  page 90 : A = PVCCIO_CPU0 ; B = PU_CPU0_SAFE_MODE_BOOT
R1C32  RES  1.00K 1% CHIP  pkg 0402  page 156 : A = GND ; B = PD_PIROM_CPU1_ADDR2

(kicad_pcb
	(version 20260206)
	(generator "pcbnew")
	(generator_version "10.0")
	(general
		(thickness 1.6)
		(legacy_teardrops no)
	)
	(paper "A4")
	(title_block
		(title "Wiwynn_Tioga_Pass_MB.brd")
		(comment 1 "Tioga Pass / footprints 1025-1027 of 4770")
	)
	(layers
		(0 "F.Cu" signal "TOP")
		(4 "In1.Cu" signal "L2GND")
		(6 "In2.Cu" signal "L3")
		(8 "In3.Cu" signal "L4GND")
		(10 "In4.Cu" signal "L5")
		(12 "In5.Cu" signal "L6GND")
		(14 "In6.Cu" signal "L7VCC")
		(16 "In7.Cu" signal "L8VCC")
		(18 "In8.Cu" signal "L9GND")
		(20 "In9.Cu" signal "L10")
		(22 "In10.Cu" signal "L11GND")
		(24 "In11.Cu" signal "L12")
		(26 "In12.Cu" signal "L13GND")
		(2 "B.Cu" signal "BOTTOM")
		(9 "F.Adhes" user "F.Adhesive")
		(11 "B.Adhes" user "B.Adhesive")
		(13 "F.Paste" user "Package Geometry/Pastemask Top")
		(15 "B.Paste" user "Package Geometry/Pastemask Bottom")
		(5 "F.SilkS" user "Ref Des/Silkscreen Top")
		(7 "B.SilkS" user "Ref Des/Silkscreen Bottom")
		(1 "F.Mask" user "Board Geometry/Soldermask Top")
		(3 "B.Mask" user "Board Geometry/Soldermask Bottom")
		(17 "Dwgs.User" user "User.Drawings")
		(19 "Cmts.User" user "User.Comments")
		(21 "Eco1.User" user "User.Eco1")
		(23 "Eco2.User" user "User.Eco2")
		(25 "Edge.Cuts" user "Board Geometry/Outline")
		(27 "Margin" user)
		(31 "F.CrtYd" user "Package Geometry/Place Bound Top")
		(29 "B.CrtYd" user "Package Geometry/Place Bound Bottom")
		(35 "F.Fab" user "Ref Des/Assembly Top")
		(33 "B.Fab" user "Ref Des/Assembly Bottom")
	)
	(footprint ""
		(layer "F.Cu")
		(at 28.7274 -105.3338 90)
		(property "Reference" "R1C32"
			(at 0 0 90)
			(layer "F.SilkS")
			(hide yes)
			(effects
				(font
					(size 1.27 1.27)
				)
			)
		)
		(property "Value" ""
			(at 0 0 90)
			(layer "F.Fab")
			(effects
				(font
					(size 1.27 1.27)
				)
			)
		)
		(duplicate_pad_numbers_are_jumpers no)
		(fp_poly
			(pts
				(xy -0.2794 -0.1016) (xy 0.2794 -0.1016) (xy 0.2794 0.9906) (xy -0.2794 0.9906)
			)
			(stroke
				(width 0)
				(type default)
			)
			(fill no)
			(layer "F.CrtYd")
		)
		(fp_line
			(start 0.2794 -0.1016)
			(end -0.2794 -0.1016)
			(stroke
				(width 0.1)
				(type default)
			)
			(layer "F.Fab")
		)
		(fp_line
			(start -0.2794 -0.1016)
			(end -0.2794 0.9906)
			(stroke
				(width 0.1)
				(type default)
			)
			(layer "F.Fab")
		)
		(fp_line
			(start 0.2794 0.9906)
			(end 0.2794 -0.1016)
			(stroke
				(width 0.1)
				(type default)
			)
			(layer "F.Fab")
		)
		(fp_line
			(start -0.2794 0.9906)
			(end 0.2794 0.9906)
			(stroke
				(width 0.1)
				(type default)
			)
			(layer "F.Fab")
		)
		(pad "1" smd rect
			(at 0 0 90)
			(size 0.508 0.508)
			(layers "F.Cu" "F.Mask" "F.Paste")
			(net "GND")
		)
		(pad "2" smd rect
			(at 0 0.889 90)
			(size 0.508 0.508)
			(layers "F.Cu" "F.Mask" "F.Paste")
			(net "PD_PIROM_CPU1_ADDR2")
		)
		(zone
			(layer "F.Cu")
			(hatch none 0.5)
			(connect_pads
				(clearance 0)
			)
			(min_thickness 0.25)
			(keepout
				(tracks allowed)
				(vias not_allowed)
				(pads allowed)
				(copperpour not_allowed)
				(footprints allowed)
			)
			(placement
				(enabled no)
				(sheetname "")
			)
			(fill
				(thermal_gap 0.5)
				(thermal_bridge_width 0.5)
				(island_removal_mode 0)
			)
			(polygon
				(pts
					(xy 28.9814 -105.0798) (xy 28.9814 -105.5878) (xy 29.3624 -105.5878) (xy 29.3624 -105.0798)
				)
			)
		)
		(zone
			(layer "F.Cu")
			(hatch none 0.5)
			(connect_pads
				(clearance 0)
			)
			(min_thickness 0.25)
			(keepout
				(tracks not_allowed)
				(vias allowed)
				(pads allowed)
				(copperpour not_allowed)
				(footprints allowed)
			)
			(placement
				(enabled no)
				(sheetname "")
			)
			(fill
				(thermal_gap 0.5)
				(thermal_bridge_width 0.5)
				(island_removal_mode 0)
			)
			(polygon
				(pts
					(xy 29.3624 -105.0798) (xy 29.3624 -105.5878) (xy 28.9814 -105.5878) (xy 28.9814 -105.0798)
				)
			)
		)
	)
	(footprint ""
		(layer "F.Cu")
		(at 323.10324 -131.34086)
		(property "Reference" "R6B1"
			(at 0 0 0)
			(layer "F.SilkS")
			(hide yes)
			(effects
				(font
					(size 1.27 1.27)
				)
			)
		)
		(property "Value" ""
			(at 0 0 0)
			(layer "F.Fab")
			(effects
				(font
					(size 1.27 1.27)
				)
			)
		)
		(duplicate_pad_numbers_are_jumpers no)
		(fp_poly
			(pts
				(xy -0.2794 -0.1016) (xy 0.2794 -0.1016) (xy 0.2794 0.9906) (xy -0.2794 0.9906)
			)
			(stroke
				(width 0)
				(type default)
			)
			(fill no)
			(layer "F.CrtYd")
		)
		(fp_line
			(start -0.2794 -0.1016)
			(end -0.2794 0.9906)
			(stroke
				(width 0.1)
				(type default)
			)
			(layer "F.Fab")
		)
		(fp_line
			(start -0.2794 0.9906)
			(end 0.2794 0.9906)
			(stroke
				(width 0.1)
				(type default)
			)
			(layer "F.Fab")
		)
		(fp_line
			(start 0.2794 -0.1016)
			(end -0.2794 -0.1016)
			(stroke
				(width 0.1)
				(type default)
			)
			(layer "F.Fab")
		)
		(fp_line
			(start 0.2794 0.9906)
			(end 0.2794 -0.1016)
			(stroke
				(width 0.1)
				(type default)
			)
			(layer "F.Fab")
		)
		(pad "1" smd rect
			(at 0 0)
			(size 0.508 0.508)
			(layers "F.Cu" "F.Mask" "F.Paste")
			(net "PVCCIO_CPU0")
		)
		(pad "2" smd rect
			(at 0 0.889)
			(size 0.508 0.508)
			(layers "F.Cu" "F.Mask" "F.Paste")
			(net "SVID_ALERT1_CPU0_R_N")
		)
		(zone
			(layer "F.Cu")
			(hatch none 0.5)
			(connect_pads
				(clearance 0)
			)
			(min_thickness 0.25)
			(keepout
				(tracks allowed)
				(vias not_allowed)
				(pads allowed)
				(copperpour not_allowed)
				(footprints allowed)
			)
			(placement
				(enabled no)
				(sheetname "")
			)
			(fill
				(thermal_gap 0.5)
				(thermal_bridge_width 0.5)
				(island_removal_mode 0)
			)
			(polygon
				(pts
					(xy 322.84924 -131.08686) (xy 323.35724 -131.08686) (xy 323.35724 -130.70586) (xy 322.84924 -130.70586)
				)
			)
		)
		(zone
			(layer "F.Cu")
			(hatch none 0.5)
			(connect_pads
				(clearance 0)
			)
			(min_thickness 0.25)
			(keepout
				(tracks not_allowed)
				(vias allowed)
				(pads allowed)
				(copperpour not_allowed)
				(footprints allowed)
			)
			(placement
				(enabled no)
				(sheetname "")
			)
			(fill
				(thermal_gap 0.5)
				(thermal_bridge_width 0.5)
				(island_removal_mode 0)
			)
			(polygon
				(pts
					(xy 322.84924 -130.70586) (xy 323.35724 -130.70586) (xy 323.35724 -131.08686) (xy 322.84924 -131.08686)
				)
			)
		)
	)
	(footprint ""
		(layer "F.Cu")
		(at 276.352 -69.977)
		(property "Reference" "R6D13"
			(at 0 0 0)
			(layer "F.SilkS")
			(hide yes)
			(effects
				(font
					(size 1.27 1.27)
				)
			)
		)
		(property "Value" ""
			(at 0 0 0)
			(layer "F.Fab")
			(effects
				(font
					(size 1.27 1.27)
				)
			)
		)
		(duplicate_pad_numbers_are_jumpers no)
		(fp_poly
			(pts
				(xy -0.2794 -0.1016) (xy 0.2794 -0.1016) (xy 0.2794 0.9906) (xy -0.2794 0.9906)
			)
			(stroke
				(width 0)
				(type default)
			)
			(fill no)
			(layer "F.CrtYd")
		)
		(fp_line
			(start -0.2794 -0.1016)
			(end -0.2794 0.9906)
			(stroke
				(width 0.1)
				(type default)
			)
			(layer "F.Fab")
		)
		(fp_line
			(start -0.2794 0.9906)
			(end 0.2794 0.9906)
			(stroke
				(width 0.1)
				(type default)
			)
			(layer "F.Fab")
		)
		(fp_line
			(start 0.2794 -0.1016)
			(end -0.2794 -0.1016)
			(stroke
				(width 0.1)
				(type default)
			)
			(layer "F.Fab")
		)
		(fp_line
			(start 0.2794 0.9906)
			(end 0.2794 -0.1016)
			(stroke
				(width 0.1)
				(type default)
			)
			(layer "F.Fab")
		)
		(pad "1" smd rect
			(at 0 0)
			(size 0.508 0.508)
			(layers "F.Cu" "F.Mask" "F.Paste")
			(net "PVCCIO_CPU0")
		)
		(pad "2" smd rect
			(at 0 0.889)
			(size 0.508 0.508)
			(layers "F.Cu" "F.Mask" "F.Paste")
			(net "PU_CPU0_SAFE_MODE_BOOT")
		)
		(zone
			(layer "F.Cu")
			(hatch none 0.5)
			(connect_pads
				(clearance 0)
			)
			(min_thickness 0.25)
			(keepout
				(tracks allowed)
				(vias not_allowed)
				(pads allowed)
				(copperpour not_allowed)
				(footprints allowed)
			)
			(placement
				(enabled no)
				(sheetname "")
			)
			(fill
				(thermal_gap 0.5)
				(thermal_bridge_width 0.5)
				(island_removal_mode 0)
			)
			(polygon
				(pts
					(xy 276.098 -69.723) (xy 276.606 -69.723) (xy 276.606 -69.342) (xy 276.098 -69.342)
				)
			)
		)
		(zone
			(layer "F.Cu")
			(hatch none 0.5)
			(connect_pads
				(clearance 0)
			)
			(min_thickness 0.25)
			(keepout
				(tracks not_allowed)
				(vias allowed)
				(pads allowed)
				(copperpour not_allowed)
				(footprints allowed)
			)
			(placement
				(enabled no)
				(sheetname "")
			)
			(fill
				(thermal_gap 0.5)
				(thermal_bridge_width 0.5)
				(island_removal_mode 0)
			)
			(polygon
				(pts
					(xy 276.098 -69.342) (xy 276.606 -69.342) (xy 276.606 -69.723) (xy 276.098 -69.723)
				)
			)
		)
	)
)
